FILE_TYPE = CONNECTIVITY;
{Allegro Design Entry HDL 17.4-2019 S026 (4007227) 1/17/2022}
"PAGE_NUMBER" = 168;
0"NC";
1"GND\g";
2"GND\g";
3"GND\g";
4"GND\g";
5"GND\g";
6"GND\g";
7"GND\g";
8"GND\g";
9"GND\g";
10"GND\g";
11"GND\g";
12"GND\g";
13"PVDDCR_SOC_P0\g";
14"GND\g";
15"GND\g";
16"GND\g";
17"GND\g";
18"GND\g";
19"GND\g";
20"GND\g";
21"GND\g";
22"PVDDCR_CPU0_P0\g";
23"GND\g";
24"GND\g";
25"VSENSE_VSS_SENSE_A_P0";
26"SVID_PVDDCR_CPU0_P0_SVTO";
27"SVID_PVDDCR_CPU0_P0_SVD_R";
28"SVID_PVDDCR_CPU0_P0_SVC_R";
29"VSENSE_PVDDCR_SOC_P0_DP";
30"VSENSE_VSS_SENSE_A_P0";
31"PVDDCR_CPU0_P0_OCP_N_R";
32"NC_PVDDCR_CPU0_P0_IMON8";
33"PVDDCR_CPU0_P0_IMON1";
34"PVDDCR_CPU0_P0_VCC";
35"SVID_PVDDCR_CPU0_P0_SVTI_R";
36"PVDDCR_CPU0_P0_PMSCL_R";
37"SVID_PVDDCR_CPU0_P0_SVC_R1";
38"PVDDCR_CPU0_P0_IMON6";
39"SVID_PVDDCR_CPU0_P0_SVTO_R";
40"PVDDCR_CPU0_P0_RESET_N_R";
41"NC_PVDDCR_CPU0_P0_IMON7";
42"PWRGD_PVDDCR_SOC_P0_R";
43"SVID_PVDDCR_CPU0_P0_SVD_R1";
44"PVDDCR_CPU0_P0_PMALERT_R";
45"PVDDCR_CPU0_P0_EN_R";
46"PVDDCR_CPU0_P0_PMSDA_R";
47"NC_PVDDCR_CPU0_P0_PWM8";
48"NC_PVDDCR_CPU0_P0_PWM7";
49"VSENSE_PVDDCR_CPU0_P0_VSEN0";
50"PVDDCR_SOC_P0_PWM2";
51"PWRGD_PVDDCR_CPU0_P0_R";
52"PVDDCR_CPU0_P0_PWM6";
53"PVDDCR_CPU0_P0_VCCS";
54"PVDDCR_CPU0_P0_VMON";
55"PVDDCR_CPU0_P0_VINSEN";
56"PVDDCR_CPU0_P0_TEMP0";
57"PVDD18_S5_P0\g";
58"VSENSE_PVDDCR_SOC_P0_VSEN1";
59"PVDDCR_SOC_P0_IMON2";
60"PVDDCR_CPU0_P0_PWM1";
61"NC_PVDDCR_CPU0_P0_PWM9";
62"NC_PVDDCR_CPU0_P0_IMON9";
63"PVDDCR_SOC_P0_PWM3";
64"PVDDCR_SOC_P0_IMON3";
65"GND\g";
66"PVDDCR_SOC_P0_EN//ADDR_CFG";
67"PVDDCR_SOC_P0_TEMP1";
68"PVDDCR_SOC_P0_PWM1";
69"PVDDCR_SOC_P0_IMON1";
70"PVDDCR_CPU0_P0_PWM5";
71"PVDDCR_CPU0_P0_IMON5";
72"PVDDCR_CPU0_P0_PWM4";
73"PVDDCR_CPU0_P0_IMON4";
74"PVDDCR_CPU0_P0_PWM3";
75"PVDDCR_CPU0_P0_IMON3";
76"PVDDCR_CPU0_P0_PWM2";
77"PVDDCR_CPU0_P0_IMON2";
78"SVID_PVDDCR_CPU0_P0_SVTI";
79"GND\g";
80"GND\g";
81"P3V3_AUX\g";
82"GND\g";
83"PVDD18_S5_P0\g";
84"P3V3_AUX\g";
85"P3V3_AUX\g";
86"GND\g";
87"P12V_AUX\g";
88"P5V_AUX\g";
89"P3V3_AUX\g";
90"GND\g"VOLTAGE"0";
91"GND\g";
92"PVDD18_S5_P0\g";
93"GND\g";
94"GND\g";
95"PWRGD_PVDDCR_CPU0_P0";
96"PVDDCR_CPU0_P0_EN";
97"SMB_SCM_2_R3_SCL";
98"PVDDCR_SOC_P0_EN_RC";
99"PWRGD_PVDDCR_SOC_P0";
100"SMB_SCM_2_R3_SDA";
101"PVDDCR_CPU0_P0_PMALERT";
102"VSENSE_PVDDCR_CPU0_P0_DP";
103"PVDDCR_SOC_P0_EN";
104"PVDDCR_CPU0_P0_OCP_N";
105"PVDDCR_SOC_P0_EN_GD";
106"PVDDCR_CPU0_P0_RESET_N";
107"SMB_SCM_2_R3_SDA";
108"SMB_SCM_2_R3_SCL";
%"Q_RES"
"2","(-7900,6375)","0","pure_quanta","I10";
;
LOCATION"PR284"
$SEC"1"
CDS_SEC"1"
MATERIAL"EMPTY"
VALUE"1K"
WATTAGE"1/16W"
PACK_TYPE"0402LF"
TOLERANCE"1%"
CDS_LIB"pure_quanta"
PART_NUMBER"CS21002FB06";
"A"
$PN"1"92;
"B"
$PN"2"78;
%"UNIVERSAL_GND"
"1","(-2150,2875)","0","pure_quanta_power","I106";
;
CDS_LIB"pure_quanta_power"
HDL_POWER"GND";
"A"94;
%"Q_RES"
"1","(-2500,3000)","0","pure_quanta","I107";
;
LOCATION"PR441"
$SEC"1"
CDS_SEC"1"
MATERIAL"CHIP"
WATTAGE"1/16W"
VALUE"0"
TOLERANCE"5%"
PACK_TYPE"0402LF"
CDS_LIB"pure_quanta"
PART_NUMBER"CS00002JB13";
"B"
$PN"2"94;
"A"
$PN"1"62;
%"Q_RES"
"1","(-2500,3300)","0","pure_quanta","I108";
;
LOCATION"PR440"
$SEC"1"
CDS_SEC"1"
WATTAGE"1/16W"
VALUE"0"
TOLERANCE"5%"
PACK_TYPE"0402LF"
MATERIAL"CHIP"
CDS_LIB"pure_quanta"
PART_NUMBER"CS00002JB13";
"B"
$PN"2"91;
"A"
$PN"1"32;
%"UNIVERSAL_GND"
"1","(-2150,3450)","0","pure_quanta_power","I109";
;
CDS_LIB"pure_quanta_power"
HDL_POWER"GND";
"A"93;
%"VCC_CORE"
"1","(-7900,6675)","0","pure_quanta_power","I11";
;
HDL_POWER"PVDD18_S5_P0"
CDS_LIB"pure_quanta_power";
"A"92;
%"UNIVERSAL_GND"
"1","(-2150,3150)","0","pure_quanta_power","I110";
;
CDS_LIB"pure_quanta_power"
HDL_POWER"GND";
"A"91;
%"Q_RES"
"1","(-2500,3600)","0","pure_quanta","I111";
;
LOCATION"PR531"
$SEC"1"
CDS_SEC"1"
PACK_TYPE"0402LF"
VALUE"0"
WATTAGE"1/16W"
TOLERANCE"5%"
MATERIAL"CHIP"
CDS_LIB"pure_quanta"
PART_NUMBER"CS00002JB13";
"B"
$PN"2"93;
"A"
$PN"1"41;
%"UNIVERSAL_GND"
"1","(-2775,5825)","0","pure_quanta_power","I117";
;
CDS_LIB"pure_quanta_power"
HDL_POWER"GND";
"A"1;
%"Q_CAP"
"1","(-2775,6050)","0","pure_quanta","I118";
;
LOCATION"PC13"
$SEC"1"
CDS_SEC"1"
MATERIAL"X7R"
TOLERANCE"10%"
VOLTAGE"25V"
PACK_TYPE"0402"
VALUE"0.1UF"
CDS_LIB"pure_quanta"
PART_NUMBER"CH4104K1B00";
"B"
$PN"2"1;
"A"
$PN"1"53;
%"UNIVERSAL_GND"
"1","(-2775,6275)","0","pure_quanta_power","I119";
;
CDS_LIB"pure_quanta_power"
HDL_POWER"GND";
"A"2;
%"UNIVERSAL_GND"
"1","(-7675,1350)","0","pure_quanta_power","I12";
;
CDS_LIB"pure_quanta_power"
HDL_POWER"GND";
"A"90;
%"Q_CAP"
"1","(-2775,6525)","0","pure_quanta","I120";
;
LOCATION"PC12"
$SEC"1"
CDS_SEC"1"
MATERIAL"X7R"
VALUE"0.1UF"
PACK_TYPE"0402"
TOLERANCE"10%"
VOLTAGE"25V"
CDS_LIB"pure_quanta"
PART_NUMBER"CH4104K1B00";
"B"
$PN"2"2;
"A"
$PN"1"34;
%"UNIVERSAL_GND"
"1","(-2500,5825)","0","pure_quanta_power","I128";
;
CDS_LIB"pure_quanta_power"
HDL_POWER"GND";
"A"3;
%"Q_CAP"
"1","(-2500,6050)","0","pure_quanta","I129";
;
LOCATION"PC470"
$SEC"1"
CDS_SEC"1"
PACK_TYPE"C0402"
VOLTAGE"6.3V"
VALUE"10UF"
TOLERANCE"20%"
MATERIAL"X6S"
CDS_LIB"pure_quanta"
PART_NUMBER"CH6101MEB03";
"B"
$PN"2"3;
"A"
$PN"1"53;
%"Q_CAP"
"1","(-7675,1600)","0","pure_quanta","I13";
;
LOCATION"C461"
$SEC"1"
CDS_SEC"1"
TOLERANCE"5%"
MATERIAL"X7R"
VOLTAGE"50V"
VALUE"1000PF"
PACK_TYPE"0402"
CDS_LIB"pure_quanta"
PART_NUMBER"TMP_QCH21006JB10";
"B"
$PN"2"90;
"A"
$PN"1"98;
%"UNIVERSAL_GND"
"1","(-2475,6275)","0","pure_quanta_power","I130";
;
CDS_LIB"pure_quanta_power"
HDL_POWER"GND";
"A"4;
%"Q_CAP"
"1","(-2475,6525)","0","pure_quanta","I131";
;
LOCATION"PC471"
$SEC"1"
CDS_SEC"1"
MATERIAL"X6S"
VOLTAGE"16V"
PACK_TYPE"C0402"
TOLERANCE"10%"
VALUE"1UF"
CDS_LIB"pure_quanta"
PART_NUMBER"CH5103KEB01";
"B"
$PN"2"4;
"A"
$PN"1"34;
%"Q_RES"
"1","(-2050,6675)","0","pure_quanta","I133";
;
LOCATION"PR316"
$SEC"1"
CDS_SEC"1"
VALUE"1"
TOLERANCE"1%"
MATERIAL"CHIP"
PACK_TYPE"0402LF"
WATTAGE"1/16W"
CDS_LIB"pure_quanta"
PART_NUMBER"CS-1002FB04";
"B"
$PN"2"89;
"A"
$PN"1"34;
%"VCC_CORE"
"1","(-1625,6775)","0","pure_quanta_power","I134";
;
HDL_POWER"P3V3_AUX"
CDS_LIB"pure_quanta_power";
"A"89;
%"RAA229620GNPHA0"
"1","(-3900,3750)","0","pure_quanta","I135";
;
LOCATION"PU42"
SEC"1"
PART_TYPE"SMLF"
MATERIAL"IC"
VALUE"RAA229620GNP#HA0"
CDS_LMAN_SYM_OUTLINE"-550,2850,500,-2850"
NEEDS_NO_SIZE"TRUE"
CDS_LIB"pure_quanta"
SEC_TYPE""
PART_NUMBER"ARF0TGP4002";
"CS10"
$PN"28"77;
"PWM10"
$PN"11"76;
"CS9"
$PN"29"75;
"PWM9"
$PN"10"74;
"CS8"
$PN"30"73;
"PWM8"
$PN"9"72;
"CS7"
$PN"31"71;
"PWM7"
$PN"8"70;
"CS0"
$PN"38"69;
"PWM0"
$PN"1"68;
"TEMP1"
$PN"43"67;
"EN1||ADDR_CFG"
$PN"42"66;
"TH_GND"
$PN"TH"65;
"OCP_L \B"
$PN"41"31;
"CS2"
$PN"36"64;
"PWM2"
$PN"3"63;
"CS3"
$PN"35"62;
"PWM3"
$PN"4"61;
"PWM11"
$PN"12"60;
"CS1"
$PN"37"59;
"RGND1"
$PN"39"30;
"VSEN1"
$PN"40"58;
"VDDIO"
$PN"19"57;
"TEMP0"
$PN"44"56;
"VINSEN"
$PN"46"55;
"VMON||IINSEN"
$PN"45"54;
"VCCS"
$PN"48"53;
"PWM6"
$PN"7"52;
"PG0"
$PN"16"51;
"PWM1"
$PN"2"50;
"VSEN0"
$PN"25"49;
"PWM5"
$PN"6"48;
"PWM4"
$PN"5"47;
"PMSDA"
$PN"13"46;
"RGND0"
$PN"26"25;
"EN0"
$PN"17"45;
"NPMALERT \B"
$PN"15"44;
"SVD"
$PN"21"43;
"PG1"
$PN"20"42;
"CS4"
$PN"34"32;
"CS5"
$PN"33"41;
"RESET_L \B"
$PN"18"40;
"SVTO"
$PN"23"39;
"CS6"
$PN"32"38;
"SVC"
$PN"22"37;
"PMSCL"
$PN"14"36;
"SVTI"
$PN"24"35;
"VCC"
$PN"47"34;
"CS11"
$PN"27"33;
%"Q_RES"
"2","(-7950,1575)","0","pure_quanta","I136";
;
LOCATION"R6089"
$SEC"1"
CDS_SEC"1"
VALUE"10K"
TOLERANCE"1%"
WATTAGE"1/16W"
MATERIAL"EMPTY"
PACK_TYPE"0402LF"
CDS_LIB"pure_quanta"
PART_NUMBER"CS31002FB08";
"A"
$PN"1"98;
"B"
$PN"2"90;
%"UNIVERSAL_GND"
"1","(-7050,1525)","7","pure_quanta_power","I137";
;
CDS_LIB"pure_quanta_power"
HDL_POWER"GND";
"A"5;
%"Q_CAP"
"2","(-6750,1525)","0","pure_quanta","I138";
;
LOCATION"C5018"
$SEC"1"
CDS_SEC"1"
MATERIAL"X7R"
TOLERANCE"5%"
VOLTAGE"50V"
PACK_TYPE"0402"
VALUE"1000PF"
CDS_LIB"pure_quanta"
PART_NUMBER"TMP_QCH21006JB10";
"A"
$PN"1"5;
"B"
$PN"2"99;
%"Q_CAP"
"2","(-6450,6625)","0","pure_quanta","I139";
;
LOCATION"C5017"
$SEC"1"
CDS_SEC"1"
PACK_TYPE"0402"
VOLTAGE"50V"
MATERIAL"X7R"
VALUE"1000PF"
TOLERANCE"5%"
CDS_LIB"pure_quanta"
PART_NUMBER"TMP_QCH21006JB10";
"A"
$PN"1"6;
"B"
$PN"2"95;
%"VCC_CORE"
"1","(-7125,1350)","0","pure_quanta_power","I14";
;
HDL_POWER"P5V_AUX"
CDS_LIB"pure_quanta_power";
"A"88;
%"UNIVERSAL_GND"
"1","(-6750,6625)","7","pure_quanta_power","I140";
;
CDS_LIB"pure_quanta_power"
HDL_POWER"GND";
"A"6;
%"UNIVERSAL_GND"
"1","(-5225,4575)","0","pure_quanta_power","I141";
;
CDS_LIB"pure_quanta_power"
HDL_POWER"GND";
"A"7;
%"Q_CAP"
"1","(-5225,4775)","0","pure_quanta","I142";
;
LOCATION"C5011"
$SEC"1"
CDS_SEC"1"
TOLERANCE"5%"
PACK_TYPE"0402"
VOLTAGE"50V"
MATERIAL"X7R"
VALUE"1000PF"
CDS_LIB"pure_quanta"
PART_NUMBER"TMP_QCH21006JB10";
"B"
$PN"2"7;
"A"
$PN"1"101;
%"CONN3_210HP1030BR1"
"1","(-6150,4675)","2","pure_quanta","I143";
;
LOCATION"PJ1"
$SEC"1"
CDS_SEC"1"
MATERIAL"IO"
PART_TYPE"THLF"
VALUE"CONN3_210-HP1-030BR1"
CDS_LIB"pure_quanta"
NEEDS_NO_SIZE"TRUE"
CDS_LMAN_SYM_OUTLINE"-50,100,50,-100"
PART_NUMBER"DFHD03MS213";
"1"
$PN"1"8;
"2"
$PN"2"100;
"3"
$PN"3"97;
%"UNIVERSAL_GND"
"1","(-5375,4725)","3","pure_quanta_power","I145";
;
CDS_LIB"pure_quanta_power"
HDL_POWER"GND";
"A"8;
%"Q_RES"
"1","(-5625,6050)","0","pure_quanta","I147";
;
LOCATION"PR8005"
$SEC"1"
CDS_SEC"1"
TOLERANCE"5%"
PACK_TYPE"0402LF"
WATTAGE"1/16W"
VALUE"0"
MATERIAL"CHIP"
CDS_LIB"pure_quanta"
PART_NUMBER"CS00002JB13";
"B"
$PN"2"37;
"A"
$PN"1"28;
%"Q_RES"
"1","(-5600,5900)","0","pure_quanta","I148";
;
LOCATION"PR8006"
$SEC"1"
CDS_SEC"1"
MATERIAL"CHIP"
WATTAGE"1/16W"
PACK_TYPE"0402LF"
TOLERANCE"5%"
VALUE"0"
CDS_LIB"pure_quanta"
PART_NUMBER"CS00002JB13";
"B"
$PN"2"43;
"A"
$PN"1"27;
%"Q_RES"
"1","(-6825,1225)","0","pure_quanta","I15";
;
LOCATION"PR290"
$SEC"1"
CDS_SEC"1"
TOLERANCE"1%"
VALUE"40.2K"
WATTAGE"1/16W"
PACK_TYPE"0402LF"
MATERIAL"CHIP"
CDS_LIB"pure_quanta"
PART_NUMBER"CS34022FB04";
"B"
$PN"2"54;
"A"
$PN"1"88;
%"MOSFET_N"
"1","(-7400,1925)","0","pure_quanta","I17";
;
LOCATION"PQ17"
$SEC"1"
CDS_SEC"1"
MATERIAL"IC"
VALUE"BSS138K"
MANUF_PN"BSS138K"
CDS_LIB"pure_quanta"
CDS_LMAN_SYM_OUTLINE"-50,50,100,-150"
PACK_TYPE"SMLF"
PART_NUMBER"BAM138K0000";
"GATE"
$PN"G"98;
"SOURCE"
$PN"S"86;
"DRAIN"
$PN"D"105;
%"Q_RES"
"2","(-7350,2425)","0","pure_quanta","I18";
;
LOCATION"PR285"
$SEC"1"
CDS_SEC"1"
PACK_TYPE"0402LF"
VALUE"1K"
TOLERANCE"1%"
MATERIAL"CHIP"
WATTAGE"1/16W"
CDS_LIB"pure_quanta"
PART_NUMBER"CS21002FB06";
"A"
$PN"1"84;
"B"
$PN"2"105;
%"MOSFET_PCH_GDS_ESD_PROTECTED"
"1","(-6700,2250)","6","pure_quanta","I19";
;
LOCATION"PQ13"
$SEC"1"
CDS_SEC"1"
MATERIAL"IC"
VALUE"PJA3415AE"
NEEDS_NO_SIZE"TRUE"
CDS_LMAN_SYM_OUTLINE"-125,150,125,-150"
CDS_LIB"pure_quanta"
PART_TYPE"SMLF"
PART_NUMBER"BAM34150008";
"S"
$PN"S"84;
"G"
$PN"G"105;
"D"
$PN"D"66;
%"Q_RES"
"1","(-8150,1825)","0","pure_quanta","I2";
;
LOCATION"R8282"
$SEC"1"
CDS_SEC"1"
VALUE"0"
PACK_TYPE"0402LF"
MATERIAL"CHIP"
WATTAGE"1/16W"
TOLERANCE"5%"
CDS_LIB"pure_quanta"
PART_NUMBER"CS00002JB13";
"B"
$PN"2"98;
"A"
$PN"1"103;
%"UNIVERSAL_GND"
"1","(-6525,800)","0","pure_quanta_power","I20";
;
CDS_LIB"pure_quanta_power"
HDL_POWER"GND";
"A"9;
%"Q_RES"
"2","(-6525,1025)","0","pure_quanta","I21";
;
LOCATION"PR5"
SEC"1"
WATTAGE"1/16W"
MATERIAL"CHIP"
PACK_TYPE"0402LF"
TOLERANCE"1%"
VALUE"10K"
CDS_LIB"pure_quanta"
SEC_TYPE"0402LF"
PART_NUMBER"CS31002FB08";
"A"
$PN"1"54;
"B"
$PN"2"9;
%"UNIVERSAL_GND"
"1","(-6050,800)","0","pure_quanta_power","I22";
;
CDS_LIB"pure_quanta_power"
HDL_POWER"GND";
"A"10;
%"Q_CAP"
"1","(-6050,1025)","0","pure_quanta","I23";
;
LOCATION"PC462"
$SEC"1"
CDS_SEC"1"
VALUE"0.1UF"
VOLTAGE"25V"
MATERIAL"X7R"
PACK_TYPE"0402"
TOLERANCE"10%"
CDS_LIB"pure_quanta"
PART_NUMBER"CH4104K1B00";
"B"
$PN"2"10;
"A"
$PN"1"54;
%"Q_RES"
"1","(-5900,1400)","0","pure_quanta","I24";
;
LOCATION"R8299"
$SEC"1"
CDS_SEC"1"
MATERIAL"CHIP"
WATTAGE"1/16W"
TOLERANCE"5%"
PACK_TYPE"0402LF"
VALUE"33"
CDS_LIB"pure_quanta"
PART_NUMBER"CS03302JB10";
"B"
$PN"2"42;
"A"
$PN"1"99;
%"VCC_CORE"
"1","(-5750,1125)","0","pure_quanta_power","I25";
;
HDL_POWER"P12V_AUX"
CDS_LIB"pure_quanta_power";
"A"87;
%"UNIVERSAL_GND"
"1","(-6675,1575)","0","pure_quanta_power","I26";
;
CDS_LIB"pure_quanta_power"
HDL_POWER"GND";
"A"86;
%"Q_RES"
"2","(-6675,1775)","0","pure_quanta","I27";
;
LOCATION"PR292"
$SEC"1"
CDS_SEC"1"
PACK_TYPE"0402LF"
VALUE"681"
TOLERANCE"1%"
WATTAGE"1/16W"
MATERIAL"CHIP"
CDS_LIB"pure_quanta"
PART_NUMBER"CS16812FB02";
"A"
$PN"1"66;
"B"
$PN"2"86;
%"Q_RES"
"1","(-5900,1650)","0","pure_quanta","I28";
;
LOCATION"R8298"
$SEC"1"
CDS_SEC"1"
WATTAGE"1/16W"
VALUE"1K"
PACK_TYPE"0402LF"
MATERIAL"CHIP"
TOLERANCE"1%"
CDS_LIB"pure_quanta"
PART_NUMBER"CS21002FB06";
"B"
$PN"2"42;
"A"
$PN"1"85;
%"VCC_CORE"
"1","(-6175,1800)","0","pure_quanta_power","I29";
;
HDL_POWER"P3V3_AUX"
CDS_LIB"pure_quanta_power";
"A"85;
%"UNIVERSAL_GND"
"1","(-8100,5175)","0","pure_quanta_power","I3";
;
CDS_LIB"pure_quanta_power"
HDL_POWER"GND";
"A"11;
%"VCC_CORE"
"1","(-5850,2200)","0","pure_quanta_power","I30";
;
HDL_POWER"PVDD18_S5_P0"
CDS_LIB"pure_quanta_power";
"A"57;
%"VCC_CORE"
"1","(-7350,2650)","0","pure_quanta_power","I31";
;
HDL_POWER"P3V3_AUX"
CDS_LIB"pure_quanta_power";
"A"84;
%"Q_RES"
"2","(-6625,2925)","0","pure_quanta","I36";
;
LOCATION"PR297"
$SEC"1"
CDS_SEC"1"
PACK_TYPE"0402LF"
VALUE"49.9"
MATERIAL"CHIP"
WATTAGE"1/16W"
TOLERANCE"1%"
CDS_LIB"pure_quanta"
PART_NUMBER"CS04992FB07";
"A"
$PN"1"30;
"B"
$PN"2"12;
%"UNIVERSAL_GND"
"1","(-6625,2725)","0","pure_quanta_power","I37";
;
CDS_LIB"pure_quanta_power"
HDL_POWER"GND";
"A"12;
%"Q_RES"
"2","(-8100,5425)","0","pure_quanta","I4";
;
LOCATION"PR283"
$SEC"1"
CDS_SEC"1"
PACK_TYPE"0402LF"
MATERIAL"CHIP"
VALUE"0"
WATTAGE"1/16W"
TOLERANCE"5%"
CDS_LIB"pure_quanta"
PART_NUMBER"CS00002JB13";
"A"
$PN"1"78;
"B"
$PN"2"11;
%"Q_RES"
"2","(-6625,3525)","0","pure_quanta","I40";
;
LOCATION"PR296"
$SEC"1"
CDS_SEC"1"
VALUE"49.9"
PACK_TYPE"0402LF"
MATERIAL"CHIP"
WATTAGE"1/16W"
TOLERANCE"1%"
CDS_LIB"pure_quanta"
PART_NUMBER"CS04992FB07";
"A"
$PN"1"13;
"B"
$PN"2"29;
%"VCC_CORE"
"1","(-6150,2925)","0","pure_quanta_power","I41";
;
HDL_POWER"PVDD18_S5_P0"
CDS_LIB"pure_quanta_power";
"A"83;
%"Q_RES"
"1","(-5700,2800)","0","pure_quanta","I42";
;
LOCATION"R8317"
$SEC"1"
CDS_SEC"1"
VALUE"1K"
TOLERANCE"1%"
PACK_TYPE"0402LF"
MATERIAL"CHIP"
WATTAGE"1/16W"
CDS_LIB"pure_quanta"
PART_NUMBER"CS21002FB06";
"B"
$PN"2"40;
"A"
$PN"1"83;
%"VCC_CORE"
"1","(-6625,3700)","0","pure_quanta_power","I43";
;
HDL_POWER"PVDDCR_SOC_P0"
CDS_LIB"pure_quanta_power";
"A"13;
%"Q_RES"
"2","(-6625,4025)","0","pure_quanta","I44";
;
LOCATION"PR295"
$SEC"1"
CDS_SEC"1"
WATTAGE"1/16W"
MATERIAL"CHIP"
PACK_TYPE"0402LF"
VALUE"49.9"
TOLERANCE"1%"
CDS_LIB"pure_quanta"
PART_NUMBER"CS04992FB07";
"A"
$PN"1"25;
"B"
$PN"2"14;
%"UNIVERSAL_GND"
"1","(-6625,3825)","0","pure_quanta_power","I45";
;
CDS_LIB"pure_quanta_power"
HDL_POWER"GND";
"A"14;
%"UNIVERSAL_GND"
"1","(-5250,650)","0","pure_quanta_power","I46";
;
CDS_LIB"pure_quanta_power"
HDL_POWER"GND";
"A"15;
%"Q_RES"
"2","(-5250,850)","0","pure_quanta","I47";
;
LOCATION"PR599"
$SEC"1"
CDS_SEC"1"
VALUE"4.99K"
TOLERANCE"1%"
MATERIAL"EMPTY"
WATTAGE"1/16W"
PACK_TYPE"0402LF"
CDS_LIB"pure_quanta"
PART_NUMBER"CS24992FB07";
"A"
$PN"1"55;
"B"
$PN"2"15;
%"Q_RES"
"1","(-5550,1050)","0","pure_quanta","I48";
;
LOCATION"PR314"
$SEC"1"
CDS_SEC"1"
TOLERANCE"5%"
VALUE"0"
MATERIAL"CHIP"
PACK_TYPE"0402LF"
WATTAGE"1/16W"
CDS_LIB"pure_quanta"
PART_NUMBER"CS00002JB13";
"B"
$PN"2"55;
"A"
$PN"1"87;
%"UNIVERSAL_GND"
"1","(-4875,650)","0","pure_quanta_power","I49";
;
CDS_LIB"pure_quanta_power"
HDL_POWER"GND";
"A"16;
%"UNIVERSAL_GND"
"1","(-7850,5175)","0","pure_quanta_power","I5";
;
CDS_LIB"pure_quanta_power"
HDL_POWER"GND";
"A"17;
%"Q_CAP"
"1","(-4875,875)","0","pure_quanta","I50";
;
LOCATION"PC7"
SEC"1"
MATERIAL"X7R"
TOLERANCE"10%"
VALUE"0.1UF"
VOLTAGE"25V"
PACK_TYPE"0402"
CDS_LIB"pure_quanta"
SEC_TYPE"0402"
PART_NUMBER"CH4104K1B00";
"B"
$PN"2"16;
"A"
$PN"1"55;
%"Q_CAP"
"2","(-5225,1650)","0","pure_quanta","I51";
;
LOCATION"C465"
$SEC"1"
CDS_SEC"1"
TOLERANCE"5%"
VOLTAGE"50V"
PACK_TYPE"0402"
VALUE"1000PF"
MATERIAL"EMPTY"
CDS_LIB"pure_quanta"
PART_NUMBER"TMP_QCH21006JB10";
"A"
$PN"1"42;
"B"
$PN"2"82;
%"Q_CAP"
"2","(-5250,2125)","0","pure_quanta","I52";
;
LOCATION"PC466"
$SEC"1"
CDS_SEC"1"
TOLERANCE"10%"
MATERIAL"X7R"
VOLTAGE"6.3V"
PACK_TYPE"0402"
VALUE"1UF"
CDS_LIB"pure_quanta"
PART_NUMBER"CH5101K1B01";
"A"
$PN"1"57;
"B"
$PN"2"18;
%"UNIVERSAL_GND"
"1","(-4900,1525)","0","pure_quanta_power","I53";
;
CDS_LIB"pure_quanta_power"
HDL_POWER"GND";
"A"82;
%"Q_RES"
"1","(-5000,2375)","0","pure_quanta","I54";
;
LOCATION"R8313"
$SEC"1"
CDS_SEC"1"
PACK_TYPE"0402LF"
TOLERANCE"1%"
VALUE"1K"
WATTAGE"1/16W"
MATERIAL"CHIP"
CDS_LIB"pure_quanta"
PART_NUMBER"CS21002FB06";
"B"
$PN"2"31;
"A"
$PN"1"57;
%"UNIVERSAL_GND"
"1","(-4850,2125)","1","pure_quanta_power","I55";
;
CDS_LIB"pure_quanta_power"
HDL_POWER"GND";
"A"18;
%"UNIVERSAL_GND"
"1","(-4675,850)","0","pure_quanta_power","I56";
;
CDS_LIB"pure_quanta_power"
HDL_POWER"GND";
"A"65;
%"Q_RES"
"1","(-5550,2650)","0","pure_quanta","I57";
;
LOCATION"R315"
$SEC"1"
CDS_SEC"1"
TOLERANCE"1%"
VALUE"49.9"
PACK_TYPE"0402LF"
WATTAGE"1/16W"
MATERIAL"CHIP"
CDS_LIB"pure_quanta"
PART_NUMBER"CS04992FB07";
"B"
$PN"2"40;
"A"
$PN"1"106;
%"Q_RES"
"1","(-5550,2500)","0","pure_quanta","I58";
;
LOCATION"R8301"
$SEC"1"
CDS_SEC"1"
VALUE"0"
WATTAGE"1/16W"
MATERIAL"CHIP"
TOLERANCE"5%"
PACK_TYPE"0402LF"
CDS_LIB"pure_quanta"
PART_NUMBER"CS00002JB13";
"B"
$PN"2"31;
"A"
$PN"1"104;
%"Q_RES"
"1","(-5525,3350)","0","pure_quanta","I59";
;
LOCATION"PR307"
$SEC"1"
CDS_SEC"1"
VALUE"0"
MATERIAL"CHIP"
TOLERANCE"5%"
WATTAGE"1/16W"
PACK_TYPE"0402LF"
CDS_LIB"pure_quanta"
PART_NUMBER"CS00002JB13";
"B"
$PN"2"58;
"A"
$PN"1"29;
%"Q_RES"
"2","(-7850,5425)","0","pure_quanta","I6";
;
LOCATION"R8286"
$SEC"1"
CDS_SEC"1"
PACK_TYPE"0402LF"
MATERIAL"EMPTY"
TOLERANCE"1%"
VALUE"1K"
WATTAGE"1/16W"
CDS_LIB"pure_quanta"
PART_NUMBER"CS21002FB06";
"A"
$PN"1"26;
"B"
$PN"2"17;
%"Q_CAP"
"1","(-5250,3225)","0","pure_quanta","I60";
;
LOCATION"PC464"
$SEC"1"
CDS_SEC"1"
VALUE"3300PF"
VOLTAGE"50V"
TOLERANCE"10%"
MATERIAL"X7R"
PACK_TYPE"0402"
CDS_LIB"pure_quanta"
PART_NUMBER"TMP_QCH2336K1B12";
"B"
$PN"2"30;
"A"
$PN"1"58;
%"Q_RES"
"1","(-5600,4450)","0","pure_quanta","I61";
;
LOCATION"PR306"
$SEC"1"
CDS_SEC"1"
TOLERANCE"5%"
VALUE"0"
WATTAGE"1/16W"
MATERIAL"CHIP"
PACK_TYPE"0402LF"
CDS_LIB"pure_quanta"
PART_NUMBER"CS00002JB13";
"B"
$PN"2"49;
"A"
$PN"1"102;
%"Q_CAP"
"1","(-5325,4325)","0","pure_quanta","I62";
;
LOCATION"PC463"
$SEC"1"
CDS_SEC"1"
MATERIAL"X7R"
PACK_TYPE"0402"
VOLTAGE"50V"
TOLERANCE"10%"
VALUE"3300PF"
CDS_LIB"pure_quanta"
PART_NUMBER"TMP_QCH2336K1B12";
"B"
$PN"2"25;
"A"
$PN"1"49;
%"UNIVERSAL_GND"
"1","(-7625,5175)","0","pure_quanta_power","I63";
;
CDS_LIB"pure_quanta_power"
HDL_POWER"GND";
"A"19;
%"Q_CAP"
"1","(-7625,5425)","0","pure_quanta","I64";
;
LOCATION"C298"
$SEC"1"
CDS_SEC"1"
VALUE"10PF"
PACK_TYPE"0402"
MATERIAL"EMPTY"
TOLERANCE"5%"
VOLTAGE"50V"
CDS_LIB"pure_quanta"
PART_NUMBER"CH01006JB08";
"B"
$PN"2"19;
"A"
$PN"1"26;
%"UNIVERSAL_GND"
"1","(-7400,5175)","0","pure_quanta_power","I65";
;
CDS_LIB"pure_quanta_power"
HDL_POWER"GND";
"A"20;
%"Q_CAP"
"1","(-7400,5425)","0","pure_quanta","I66";
;
LOCATION"C299"
$SEC"1"
CDS_SEC"1"
MATERIAL"EMPTY"
TOLERANCE"5%"
PACK_TYPE"0402"
VOLTAGE"50V"
VALUE"10PF"
CDS_LIB"pure_quanta"
PART_NUMBER"CH01006JB08";
"B"
$PN"2"20;
"A"
$PN"1"27;
%"UNIVERSAL_GND"
"1","(-7175,5175)","0","pure_quanta_power","I67";
;
CDS_LIB"pure_quanta_power"
HDL_POWER"GND";
"A"21;
%"Q_CAP"
"1","(-7175,5425)","0","pure_quanta","I68";
;
LOCATION"C302"
$SEC"1"
CDS_SEC"1"
MATERIAL"EMPTY"
VALUE"10PF"
VOLTAGE"50V"
TOLERANCE"5%"
PACK_TYPE"0402"
CDS_LIB"pure_quanta"
PART_NUMBER"CH01006JB08";
"B"
$PN"2"21;
"A"
$PN"1"28;
%"Q_RES"
"2","(-7550,6375)","0","pure_quanta","I69";
;
LOCATION"R8287"
$SEC"1"
CDS_SEC"1"
WATTAGE"1/16W"
VALUE"1K"
TOLERANCE"1%"
MATERIAL"EMPTY"
PACK_TYPE"0402LF"
CDS_LIB"pure_quanta"
PART_NUMBER"CS21002FB06";
"A"
$PN"1"92;
"B"
$PN"2"26;
%"Q_RES"
"2","(-7250,6375)","0","pure_quanta","I70";
;
LOCATION"R8289"
$SEC"1"
CDS_SEC"1"
TOLERANCE"1%"
VALUE"1K"
WATTAGE"1/16W"
PACK_TYPE"0402LF"
MATERIAL"EMPTY"
CDS_LIB"pure_quanta"
PART_NUMBER"CS21002FB06";
"A"
$PN"1"92;
"B"
$PN"2"27;
%"Q_RES"
"2","(-6975,6375)","0","pure_quanta","I71";
;
LOCATION"R8293"
$SEC"1"
CDS_SEC"1"
WATTAGE"1/16W"
PACK_TYPE"0402LF"
TOLERANCE"1%"
MATERIAL"EMPTY"
VALUE"1K"
CDS_LIB"pure_quanta"
PART_NUMBER"CS21002FB06";
"A"
$PN"1"92;
"B"
$PN"2"28;
%"Q_RES"
"2","(-6625,4650)","0","pure_quanta","I72";
;
LOCATION"PR294"
$SEC"1"
CDS_SEC"1"
WATTAGE"1/16W"
VALUE"49.9"
MATERIAL"CHIP"
PACK_TYPE"0402LF"
TOLERANCE"1%"
CDS_LIB"pure_quanta"
PART_NUMBER"CS04992FB07";
"A"
$PN"1"22;
"B"
$PN"2"102;
%"VCC_CORE"
"1","(-6625,4850)","0","pure_quanta_power","I73";
;
HDL_POWER"PVDDCR_CPU0_P0"
CDS_LIB"pure_quanta_power";
"A"22;
%"VCC_CORE"
"1","(-6100,6900)","0","pure_quanta_power","I81";
;
HDL_POWER"P3V3_AUX"
CDS_LIB"pure_quanta_power";
"A"81;
%"Q_RES"
"1","(-5700,6775)","0","pure_quanta","I82";
;
LOCATION"R8300"
$SEC"1"
CDS_SEC"1"
MATERIAL"CHIP"
PACK_TYPE"0402LF"
TOLERANCE"1%"
VALUE"1K"
WATTAGE"1/16W"
CDS_LIB"pure_quanta"
PART_NUMBER"CS21002FB06";
"B"
$PN"2"51;
"A"
$PN"1"81;
%"Q_RES"
"1","(-5500,5050)","0","pure_quanta","I83";
;
LOCATION"R8310"
$SEC"1"
CDS_SEC"1"
PACK_TYPE"0402LF"
WATTAGE"1/16W"
VALUE"33"
MATERIAL"CHIP"
TOLERANCE"5%"
CDS_LIB"pure_quanta"
PART_NUMBER"CS03302JB10";
"B"
$PN"2"44;
"A"
$PN"1"101;
%"Q_RES"
"1","(-5500,5200)","0","pure_quanta","I84";
;
LOCATION"R8309"
$SEC"1"
CDS_SEC"1"
MATERIAL"CHIP"
PACK_TYPE"0402LF"
VALUE"0"
TOLERANCE"5%"
WATTAGE"1/16W"
CDS_LIB"pure_quanta"
PART_NUMBER"CS00002JB13";
"B"
$PN"2"46;
"A"
$PN"1"107;
%"Q_RES"
"1","(-5500,5350)","0","pure_quanta","I85";
;
LOCATION"R8308"
$SEC"1"
CDS_SEC"1"
MATERIAL"CHIP"
VALUE"0"
PACK_TYPE"0402LF"
WATTAGE"1/16W"
TOLERANCE"5%"
CDS_LIB"pure_quanta"
PART_NUMBER"CS00002JB13";
"B"
$PN"2"36;
"A"
$PN"1"108;
%"Q_RES"
"1","(-5600,5600)","0","pure_quanta","I86";
;
LOCATION"PR305"
$SEC"1"
CDS_SEC"1"
WATTAGE"1/16W"
TOLERANCE"5%"
PACK_TYPE"0402LF"
VALUE"0"
MATERIAL"CHIP"
CDS_LIB"pure_quanta"
PART_NUMBER"CS00002JB13";
"B"
$PN"2"35;
"A"
$PN"1"78;
%"Q_RES"
"1","(-5600,5750)","0","pure_quanta","I87";
;
LOCATION"R8304"
$SEC"1"
CDS_SEC"1"
MATERIAL"CHIP"
PACK_TYPE"0402LF"
WATTAGE"1/16W"
VALUE"49.9"
TOLERANCE"1%"
CDS_LIB"pure_quanta"
PART_NUMBER"CS04992FB07";
"B"
$PN"2"39;
"A"
$PN"1"26;
%"Q_RES"
"1","(-5475,6350)","0","pure_quanta","I88";
;
LOCATION"R8312"
$SEC"1"
CDS_SEC"1"
PACK_TYPE"0402LF"
TOLERANCE"5%"
VALUE"0"
WATTAGE"1/16W"
MATERIAL"CHIP"
CDS_LIB"pure_quanta"
PART_NUMBER"CS00002JB13";
"B"
$PN"2"45;
"A"
$PN"1"96;
%"Q_RES"
"1","(-5475,6500)","0","pure_quanta","I89";
;
LOCATION"R8311"
$SEC"1"
CDS_SEC"1"
MATERIAL"CHIP"
PACK_TYPE"0402LF"
WATTAGE"1/16W"
TOLERANCE"5%"
VALUE"33"
CDS_LIB"pure_quanta"
PART_NUMBER"CS03302JB10";
"B"
$PN"2"51;
"A"
$PN"1"95;
%"Q_CAP"
"2","(-4800,6225)","0","pure_quanta","I90";
;
LOCATION"C468"
$SEC"1"
CDS_SEC"1"
VOLTAGE"50V"
PACK_TYPE"0402"
TOLERANCE"5%"
VALUE"1000PF"
MATERIAL"X7R"
CDS_LIB"pure_quanta"
PART_NUMBER"TMP_QCH21006JB10";
"A"
$PN"1"45;
"B"
$PN"2"80;
%"UNIVERSAL_GND"
"1","(-4575,6150)","0","pure_quanta_power","I91";
;
CDS_LIB"pure_quanta_power"
HDL_POWER"GND";
"A"80;
%"Q_CAP"
"2","(-4825,6775)","0","pure_quanta","I92";
;
LOCATION"C467"
$SEC"1"
CDS_SEC"1"
VALUE"1000PF"
MATERIAL"EMPTY"
PACK_TYPE"0402"
VOLTAGE"50V"
TOLERANCE"5%"
CDS_LIB"pure_quanta"
PART_NUMBER"TMP_QCH21006JB10";
"A"
$PN"1"51;
"B"
$PN"2"79;
%"UNIVERSAL_GND"
"1","(-4575,6700)","0","pure_quanta_power","I93";
;
CDS_LIB"pure_quanta_power"
HDL_POWER"GND";
"A"79;
%"UNIVERSAL_GND"
"1","(-2950,825)","0","pure_quanta_power","I94";
;
CDS_LIB"pure_quanta_power"
HDL_POWER"GND";
"A"23;
%"Q_CAP"
"1","(-2950,1100)","0","pure_quanta","I95";
;
LOCATION"PC469"
$SEC"1"
CDS_SEC"1"
MATERIAL"X7R"
TOLERANCE"10%"
VALUE"470PF"
VOLTAGE"50V"
PACK_TYPE"0402"
CDS_LIB"pure_quanta"
PART_NUMBER"TMP_QCH14706KB18";
"B"
$PN"2"23;
"A"
$PN"1"56;
%"UNIVERSAL_GND"
"1","(-2325,1175)","0","pure_quanta_power","I97";
;
CDS_LIB"pure_quanta_power"
HDL_POWER"GND";
"A"24;
%"Q_CAP"
"1","(-2325,1425)","0","pure_quanta","I98";
;
LOCATION"PC472"
$SEC"1"
CDS_SEC"1"
TOLERANCE"10%"
VOLTAGE"50V"
PACK_TYPE"0402"
MATERIAL"X7R"
VALUE"470PF"
CDS_LIB"pure_quanta"
PART_NUMBER"TMP_QCH14706KB18";
"B"
$PN"2"24;
"A"
$PN"1"67;
END.
